(kicad_pcb
	(version 20260206)
	(generator "pcbnew")
	(generator_version "10.0")
	(general
		(thickness 1.6)
		(legacy_teardrops no)
	)
	(paper "A4")
	(title_block
		(title "Bryce Canyon_F.DPB_16315-1-OCP.brd")
		(comment 1 "Bryce Canyon / footprints 226-232 of 2223")
	)
	(layers
		(0 "F.Cu" signal "TOP")
		(4 "In1.Cu" signal "L2GND")
		(6 "In2.Cu" signal "L3")
		(8 "In3.Cu" signal "L4GND")
		(10 "In4.Cu" signal "L5")
		(12 "In5.Cu" signal "L6VCC")
		(14 "In6.Cu" signal "L7VCC")
		(16 "In7.Cu" signal "L8")
		(18 "In8.Cu" signal "L9GND")
		(20 "In9.Cu" signal "L10")
		(22 "In10.Cu" signal "L11GND")
		(2 "B.Cu" signal "BOTTOM")
		(9 "F.Adhes" user "F.Adhesive")
		(11 "B.Adhes" user "B.Adhesive")
		(13 "F.Paste" user "Package Geometry/Pastemask Top")
		(15 "B.Paste" user "Package Geometry/Pastemask Bottom")
		(5 "F.SilkS" user "Ref Des/Silkscreen Top")
		(7 "B.SilkS" user "Ref Des/Silkscreen Bottom")
		(1 "F.Mask" user "Board Geometry/Soldermask Top")
		(3 "B.Mask" user "Board Geometry/Soldermask Bottom")
		(17 "Dwgs.User" user "User.Drawings")
		(19 "Cmts.User" user "User.Comments")
		(21 "Eco1.User" user "User.Eco1")
		(23 "Eco2.User" user "User.Eco2")
		(25 "Edge.Cuts" user "Board Geometry/Outline")
		(27 "Margin" user)
		(31 "F.CrtYd" user "Package Geometry/Place Bound Top")
		(29 "B.CrtYd" user "Package Geometry/Place Bound Bottom")
		(35 "F.Fab" user "Ref Des/Assembly Top")
		(33 "B.Fab" user "Ref Des/Assembly Bottom")
	)
	(footprint ""
		(layer "F.Cu")
		(at 334.980534 -21.45157)
		(property "Reference" "R80"
			(at 0 0 0)
			(layer "F.SilkS")
			(hide yes)
			(effects
				(font
					(size 1.27 1.27)
				)
			)
		)
		(property "Value" "4K7R2F-GP"
			(at 0.064008 -3.993896 0)
			(unlocked yes)
			(layer "F.Fab")
			(hide yes)
			(effects
				(font
					(size 1.016 1.016)
					(thickness 0.1524)
				)
			)
		)
		(property "Device Type" "R402H16"
			(at 0.064008 -5.517896 0)
			(unlocked yes)
			(layer "F.Fab")
			(hide yes)
			(effects
				(font
					(size 1.016 1.016)
					(thickness 0.1524)
				)
			)
		)
		(duplicate_pad_numbers_are_jumpers no)
		(fp_line
			(start -0.508 -0.9398)
			(end -0.508 0.9398)
			(stroke
				(width 0.1524)
				(type default)
			)
			(layer "F.SilkS")
		)
		(fp_line
			(start 0.508 -0.9398)
			(end -0.508 -0.9398)
			(stroke
				(width 0.1524)
				(type default)
			)
			(layer "F.SilkS")
		)
		(fp_rect
			(start -0.508 0.9398)
			(end 0.508 -0.9398)
			(stroke
				(width 0)
				(type default)
			)
			(fill no)
			(layer "F.CrtYd")
		)
		(fp_rect
			(start -0.508 0.9398)
			(end 0.508 -0.9398)
			(stroke
				(width 0)
				(type default)
			)
			(fill no)
			(layer "F.Fab")
		)
		(pad "1" smd custom
			(at 0 -0.4445)
			(size 0.1397 0.1397)
			(layers "F.Cu" "F.Mask" "F.Paste")
			(net "IO_EXP11_A1")
			(options
				(clearance outline)
				(anchor circle)
			)
			(primitives
				(gr_poly
					(pts
						(arc
							(start -0.1778 -0.2794)
							(mid -0.249642 -0.249642)
							(end -0.2794 -0.1778)
						)
						(arc
							(start -0.2794 0.1778)
							(mid -0.249642 0.249642)
							(end -0.1778 0.2794)
						)
						(arc
							(start 0.1778 0.2794)
							(mid 0.249642 0.249642)
							(end 0.2794 0.1778)
						)
						(arc
							(start 0.2794 -0.1778)
							(mid 0.249642 -0.249642)
							(end 0.1778 -0.2794)
						)
					)
					(width 0)
					(fill yes)
				)
			)
		)
		(pad "2" smd custom
			(at 0 0.4445)
			(size 0.1397 0.1397)
			(layers "F.Cu" "F.Mask" "F.Paste")
			(net "GND")
			(options
				(clearance outline)
				(anchor circle)
			)
			(primitives
				(gr_poly
					(pts
						(arc
							(start -0.1778 -0.2794)
							(mid -0.249642 -0.249642)
							(end -0.2794 -0.1778)
						)
						(arc
							(start -0.2794 0.1778)
							(mid -0.249642 0.249642)
							(end -0.1778 0.2794)
						)
						(arc
							(start 0.1778 0.2794)
							(mid 0.249642 0.249642)
							(end 0.2794 0.1778)
						)
						(arc
							(start 0.2794 -0.1778)
							(mid 0.249642 -0.249642)
							(end 0.1778 -0.2794)
						)
					)
					(width 0)
					(fill yes)
				)
			)
		)
	)
	(footprint ""
		(layer "F.Cu")
		(at 54.546246 -274.871942 -90)
		(property "Reference" "R163"
			(at 0 0 270)
			(layer "F.SilkS")
			(hide yes)
			(effects
				(font
					(size 1.27 1.27)
				)
			)
		)
		(property "Value" "0R2J-2-GP"
			(at 0.064008 -3.993896 270)
			(unlocked yes)
			(layer "F.Fab")
			(hide yes)
			(effects
				(font
					(size 1.016 1.016)
					(thickness 0.1524)
				)
			)
		)
		(property "Device Type" "R402H16"
			(at 0.064008 -5.517896 270)
			(unlocked yes)
			(layer "F.Fab")
			(hide yes)
			(effects
				(font
					(size 1.016 1.016)
					(thickness 0.1524)
				)
			)
		)
		(duplicate_pad_numbers_are_jumpers no)
		(fp_line
			(start -0.508 -0.9398)
			(end -0.508 0.9398)
			(stroke
				(width 0.1524)
				(type default)
			)
			(layer "F.SilkS")
		)
		(fp_line
			(start 0.508 -0.9398)
			(end -0.508 -0.9398)
			(stroke
				(width 0.1524)
				(type default)
			)
			(layer "F.SilkS")
		)
		(fp_rect
			(start -0.508 0.9398)
			(end 0.508 -0.9398)
			(stroke
				(width 0)
				(type default)
			)
			(fill no)
			(layer "F.CrtYd")
		)
		(fp_rect
			(start -0.508 0.9398)
			(end 0.508 -0.9398)
			(stroke
				(width 0)
				(type default)
			)
			(fill no)
			(layer "F.Fab")
		)
		(pad "1" smd custom
			(at 0 -0.4445 270)
			(size 0.1397 0.1397)
			(layers "F.Cu" "F.Mask" "F.Paste")
			(net "DRIVE_A_1_PWR")
			(options
				(clearance outline)
				(anchor circle)
			)
			(primitives
				(gr_poly
					(pts
						(arc
							(start -0.1778 -0.2794)
							(mid -0.249642 -0.249642)
							(end -0.2794 -0.1778)
						)
						(arc
							(start -0.2794 0.1778)
							(mid -0.249642 0.249642)
							(end -0.1778 0.2794)
						)
						(arc
							(start 0.1778 0.2794)
							(mid 0.249642 0.249642)
							(end 0.2794 0.1778)
						)
						(arc
							(start 0.2794 -0.1778)
							(mid 0.249642 -0.249642)
							(end 0.1778 -0.2794)
						)
					)
					(width 0)
					(fill yes)
				)
			)
		)
		(pad "2" smd custom
			(at 0 0.4445 270)
			(size 0.1397 0.1397)
			(layers "F.Cu" "F.Mask" "F.Paste")
			(net "SW_PWR_R_HDD1")
			(options
				(clearance outline)
				(anchor circle)
			)
			(primitives
				(gr_poly
					(pts
						(arc
							(start -0.1778 -0.2794)
							(mid -0.249642 -0.249642)
							(end -0.2794 -0.1778)
						)
						(arc
							(start -0.2794 0.1778)
							(mid -0.249642 0.249642)
							(end -0.1778 0.2794)
						)
						(arc
							(start 0.1778 0.2794)
							(mid 0.249642 0.249642)
							(end 0.2794 0.1778)
						)
						(arc
							(start 0.2794 -0.1778)
							(mid 0.249642 -0.249642)
							(end 0.1778 -0.2794)
						)
					)
					(width 0)
					(fill yes)
				)
			)
		)
	)
	(footprint ""
		(layer "F.Cu")
		(at 240.3602 -382.1938)
		(property "Reference" "R1158"
			(at 0 0 0)
			(layer "F.SilkS")
			(hide yes)
			(effects
				(font
					(size 1.27 1.27)
				)
			)
		)
		(property "Value" "11KR2F-L-GP"
			(at 0.064008 -3.993896 0)
			(unlocked yes)
			(layer "F.Fab")
			(hide yes)
			(effects
				(font
					(size 1.016 1.016)
					(thickness 0.1524)
				)
			)
		)
		(property "Device Type" "R402H16"
			(at 0.064008 -5.517896 0)
			(unlocked yes)
			(layer "F.Fab")
			(hide yes)
			(effects
				(font
					(size 1.016 1.016)
					(thickness 0.1524)
				)
			)
		)
		(duplicate_pad_numbers_are_jumpers no)
		(fp_line
			(start -0.508 -0.9398)
			(end -0.508 0.9398)
			(stroke
				(width 0.1524)
				(type default)
			)
			(layer "F.SilkS")
		)
		(fp_line
			(start 0.508 -0.9398)
			(end -0.508 -0.9398)
			(stroke
				(width 0.1524)
				(type default)
			)
			(layer "F.SilkS")
		)
		(fp_rect
			(start -0.508 0.9398)
			(end 0.508 -0.9398)
			(stroke
				(width 0)
				(type default)
			)
			(fill no)
			(layer "F.CrtYd")
		)
		(fp_rect
			(start -0.508 0.9398)
			(end 0.508 -0.9398)
			(stroke
				(width 0)
				(type default)
			)
			(fill no)
			(layer "F.Fab")
		)
		(pad "1" smd custom
			(at 0 -0.4445)
			(size 0.1397 0.1397)
			(layers "F.Cu" "F.Mask" "F.Paste")
			(net "MB3_P12V_PWGIN_R")
			(options
				(clearance outline)
				(anchor circle)
			)
			(primitives
				(gr_poly
					(pts
						(arc
							(start -0.1778 -0.2794)
							(mid -0.249642 -0.249642)
							(end -0.2794 -0.1778)
						)
						(arc
							(start -0.2794 0.1778)
							(mid -0.249642 0.249642)
							(end -0.1778 0.2794)
						)
						(arc
							(start 0.1778 0.2794)
							(mid 0.249642 0.249642)
							(end 0.2794 0.1778)
						)
						(arc
							(start 0.2794 -0.1778)
							(mid 0.249642 -0.249642)
							(end 0.1778 -0.2794)
						)
					)
					(width 0)
					(fill yes)
				)
			)
		)
		(pad "2" smd custom
			(at 0 0.4445)
			(size 0.1397 0.1397)
			(layers "F.Cu" "F.Mask" "F.Paste")
			(net "AGND_CURRENT_DPB")
			(options
				(clearance outline)
				(anchor circle)
			)
			(primitives
				(gr_poly
					(pts
						(arc
							(start -0.1778 -0.2794)
							(mid -0.249642 -0.249642)
							(end -0.2794 -0.1778)
						)
						(arc
							(start -0.2794 0.1778)
							(mid -0.249642 0.249642)
							(end -0.1778 0.2794)
						)
						(arc
							(start 0.1778 0.2794)
							(mid 0.249642 0.249642)
							(end 0.2794 0.1778)
						)
						(arc
							(start 0.2794 -0.1778)
							(mid 0.249642 -0.249642)
							(end 0.1778 -0.2794)
						)
					)
					(width 0)
					(fill yes)
				)
			)
		)
	)
	(footprint ""
		(layer "F.Cu")
		(at 81.625948 -45.633894)
		(property "Reference" "R745"
			(at 0 0 0)
			(layer "F.SilkS")
			(hide yes)
			(effects
				(font
					(size 1.27 1.27)
				)
			)
		)
		(property "Value" "0R2J-2-GP"
			(at 0.064008 -3.993896 0)
			(unlocked yes)
			(layer "F.Fab")
			(hide yes)
			(effects
				(font
					(size 1.016 1.016)
					(thickness 0.1524)
				)
			)
		)
		(property "Device Type" "R402H16"
			(at 0.064008 -5.517896 0)
			(unlocked yes)
			(layer "F.Fab")
			(hide yes)
			(effects
				(font
					(size 1.016 1.016)
					(thickness 0.1524)
				)
			)
		)
		(duplicate_pad_numbers_are_jumpers no)
		(fp_line
			(start -0.508 -0.9398)
			(end -0.508 0.9398)
			(stroke
				(width 0.1524)
				(type default)
			)
			(layer "F.SilkS")
		)
		(fp_line
			(start 0.508 -0.9398)
			(end -0.508 -0.9398)
			(stroke
				(width 0.1524)
				(type default)
			)
			(layer "F.SilkS")
		)
		(fp_rect
			(start -0.508 0.9398)
			(end 0.508 -0.9398)
			(stroke
				(width 0)
				(type default)
			)
			(fill no)
			(layer "F.CrtYd")
		)
		(fp_rect
			(start -0.508 0.9398)
			(end 0.508 -0.9398)
			(stroke
				(width 0)
				(type default)
			)
			(fill no)
			(layer "F.Fab")
		)
		(pad "1" smd custom
			(at 0 -0.4445)
			(size 0.1397 0.1397)
			(layers "F.Cu" "F.Mask" "F.Paste")
			(net "SW_HDD_G26")
			(options
				(clearance outline)
				(anchor circle)
			)
			(primitives
				(gr_poly
					(pts
						(arc
							(start -0.1778 -0.2794)
							(mid -0.249642 -0.249642)
							(end -0.2794 -0.1778)
						)
						(arc
							(start -0.2794 0.1778)
							(mid -0.249642 0.249642)
							(end -0.1778 0.2794)
						)
						(arc
							(start 0.1778 0.2794)
							(mid 0.249642 0.249642)
							(end 0.2794 0.1778)
						)
						(arc
							(start 0.2794 -0.1778)
							(mid 0.249642 -0.249642)
							(end 0.1778 -0.2794)
						)
					)
					(width 0)
					(fill yes)
				)
			)
		)
		(pad "2" smd custom
			(at 0 0.4445)
			(size 0.1397 0.1397)
			(layers "F.Cu" "F.Mask" "F.Paste")
			(net "SW_HDD_R26")
			(options
				(clearance outline)
				(anchor circle)
			)
			(primitives
				(gr_poly
					(pts
						(arc
							(start -0.1778 -0.2794)
							(mid -0.249642 -0.249642)
							(end -0.2794 -0.1778)
						)
						(arc
							(start -0.2794 0.1778)
							(mid -0.249642 0.249642)
							(end -0.1778 0.2794)
						)
						(arc
							(start 0.1778 0.2794)
							(mid 0.249642 0.249642)
							(end 0.2794 0.1778)
						)
						(arc
							(start 0.2794 -0.1778)
							(mid 0.249642 -0.249642)
							(end 0.1778 -0.2794)
						)
					)
					(width 0)
					(fill yes)
				)
			)
		)
	)
	(footprint ""
		(layer "F.Cu")
		(at 469.942926 -168.482518 -90)
		(property "Reference" "R672"
			(at 0 0 270)
			(layer "F.SilkS")
			(hide yes)
			(effects
				(font
					(size 1.27 1.27)
				)
			)
		)
		(property "Value" "300KR2F-GP"
			(at 0.064008 -3.993896 270)
			(unlocked yes)
			(layer "F.Fab")
			(hide yes)
			(effects
				(font
					(size 1.016 1.016)
					(thickness 0.1524)
				)
			)
		)
		(property "Device Type" "R402H16"
			(at 0.064008 -5.517896 270)
			(unlocked yes)
			(layer "F.Fab")
			(hide yes)
			(effects
				(font
					(size 1.016 1.016)
					(thickness 0.1524)
				)
			)
		)
		(duplicate_pad_numbers_are_jumpers no)
		(fp_line
			(start -0.508 -0.9398)
			(end -0.508 0.9398)
			(stroke
				(width 0.1524)
				(type default)
			)
			(layer "F.SilkS")
		)
		(fp_line
			(start 0.508 -0.9398)
			(end -0.508 -0.9398)
			(stroke
				(width 0.1524)
				(type default)
			)
			(layer "F.SilkS")
		)
		(fp_rect
			(start -0.508 0.9398)
			(end 0.508 -0.9398)
			(stroke
				(width 0)
				(type default)
			)
			(fill no)
			(layer "F.CrtYd")
		)
		(fp_rect
			(start -0.508 0.9398)
			(end 0.508 -0.9398)
			(stroke
				(width 0)
				(type default)
			)
			(fill no)
			(layer "F.Fab")
		)
		(pad "1" smd custom
			(at 0 -0.4445 270)
			(size 0.1397 0.1397)
			(layers "F.Cu" "F.Mask" "F.Paste")
			(net "SW_HDD_N23")
			(options
				(clearance outline)
				(anchor circle)
			)
			(primitives
				(gr_poly
					(pts
						(arc
							(start -0.1778 -0.2794)
							(mid -0.249642 -0.249642)
							(end -0.2794 -0.1778)
						)
						(arc
							(start -0.2794 0.1778)
							(mid -0.249642 0.249642)
							(end -0.1778 0.2794)
						)
						(arc
							(start 0.1778 0.2794)
							(mid 0.249642 0.249642)
							(end 0.2794 0.1778)
						)
						(arc
							(start 0.2794 -0.1778)
							(mid 0.249642 -0.249642)
							(end 0.1778 -0.2794)
						)
					)
					(width 0)
					(fill yes)
				)
			)
		)
		(pad "2" smd custom
			(at 0 0.4445 270)
			(size 0.1397 0.1397)
			(layers "F.Cu" "F.Mask" "F.Paste")
			(net "P12V_A")
			(options
				(clearance outline)
				(anchor circle)
			)
			(primitives
				(gr_poly
					(pts
						(arc
							(start -0.1778 -0.2794)
							(mid -0.249642 -0.249642)
							(end -0.2794 -0.1778)
						)
						(arc
							(start -0.2794 0.1778)
							(mid -0.249642 0.249642)
							(end -0.1778 0.2794)
						)
						(arc
							(start 0.1778 0.2794)
							(mid 0.249642 0.249642)
							(end 0.2794 0.1778)
						)
						(arc
							(start 0.2794 -0.1778)
							(mid 0.249642 -0.249642)
							(end 0.1778 -0.2794)
						)
					)
					(width 0)
					(fill yes)
				)
			)
		)
	)
	(footprint ""
		(layer "F.Cu")
		(at 150.136098 -301.287942)
		(property "Reference" "C96"
			(at 0 0 0)
			(layer "F.SilkS")
			(hide yes)
			(effects
				(font
					(size 1.27 1.27)
				)
			)
		)
		(property "Value" "SC4D7U25V5KX-1-GP"
			(at -0.0762 -6.1214 0)
			(unlocked yes)
			(layer "F.Fab")
			(hide yes)
			(effects
				(font
					(size 1.016 1.016)
					(thickness 0.1524)
				)
			)
		)
		(property "Device Type" "C805H58"
			(at -0.0762 -8.1534 0)
			(unlocked yes)
			(layer "F.Fab")
			(hide yes)
			(effects
				(font
					(size 1.016 1.016)
					(thickness 0.1524)
				)
			)
		)
		(duplicate_pad_numbers_are_jumpers no)
		(fp_line
			(start 0.635 0)
			(end -0.635 0)
			(stroke
				(width 0.508)
				(type default)
			)
			(layer "F.SilkS")
		)
		(fp_rect
			(start -0.9652 1.778)
			(end 0.9652 -1.778)
			(stroke
				(width 0)
				(type default)
			)
			(fill no)
			(layer "F.CrtYd")
		)
		(fp_poly
			(pts
				(xy -0.9652 -1.778) (xy 0.9652 -1.778) (xy 0.9652 1.778) (xy -0.9652 1.778)
			)
			(stroke
				(width 0)
				(type default)
			)
			(fill no)
			(layer "F.Fab")
		)
		(pad "1" smd rect
			(at 0 -0.9652)
			(size 1.397 1.143)
			(layers "F.Cu" "F.Mask" "F.Paste")
			(net "P12V_HDD4")
		)
		(pad "2" smd rect
			(at 0 0.9652)
			(size 1.397 1.143)
			(layers "F.Cu" "F.Mask" "F.Paste")
			(net "GND")
		)
	)
	(footprint ""
		(layer "F.Cu")
		(at 410.414978 -127.254)
		(property "Reference" "R338"
			(at 0 0 0)
			(layer "F.SilkS")
			(hide yes)
			(effects
				(font
					(size 1.27 1.27)
				)
			)
		)
		(property "Value" "91R3F-1-GP"
			(at -0.0254 -2.5146 0)
			(unlocked yes)
			(layer "F.Fab")
			(hide yes)
			(effects
				(font
					(size 1.016 1.016)
					(thickness 0.1524)
				)
			)
		)
		(property "Device Type" "R603H22"
			(at -0.0254 -4.0386 0)
			(unlocked yes)
			(layer "F.Fab")
			(hide yes)
			(effects
				(font
					(size 1.016 1.016)
					(thickness 0.1524)
				)
			)
		)
		(duplicate_pad_numbers_are_jumpers no)
		(fp_line
			(start -0.4826 0)
			(end -0.2032 0)
			(stroke
				(width 0.2032)
				(type default)
			)
			(layer "F.SilkS")
		)
		(fp_line
			(start 0.2032 0)
			(end 0.4826 0)
			(stroke
				(width 0.2032)
				(type default)
			)
			(layer "F.SilkS")
		)
		(fp_rect
			(start -0.5842 1.3335)
			(end 0.5842 -1.3335)
			(stroke
				(width 0)
				(type default)
			)
			(fill no)
			(layer "F.CrtYd")
		)
		(fp_rect
			(start -0.5842 1.3335)
			(end 0.5842 -1.3335)
			(stroke
				(width 0)
				(type default)
			)
			(fill no)
			(layer "F.Fab")
		)
		(pad "1" smd custom
			(at 0 -0.762)
			(size 0.2159 0.2159)
			(layers "F.Cu" "F.Mask" "F.Paste")
			(net "P5V_A_4")
			(options
				(clearance outline)
				(anchor circle)
			)
			(primitives
				(gr_poly
					(pts
						(arc
							(start -0.3302 -0.4318)
							(mid -0.402042 -0.402042)
							(end -0.4318 -0.3302)
						)
						(arc
							(start -0.4318 0.3302)
							(mid -0.402042 0.402042)
							(end -0.3302 0.4318)
						)
						(arc
							(start 0.3302 0.4318)
							(mid 0.402042 0.402042)
							(end 0.4318 0.3302)
						)
						(arc
							(start 0.4318 -0.3302)
							(mid 0.402042 -0.402042)
							(end 0.3302 -0.4318)
						)
					)
					(width 0)
					(fill yes)
				)
			)
		)
		(pad "2" smd custom
			(at 0 0.762)
			(size 0.2159 0.2159)
			(layers "F.Cu" "F.Mask" "F.Paste")
			(net "DRV_ACT_21")
			(options
				(clearance outline)
				(anchor circle)
			)
			(primitives
				(gr_poly
					(pts
						(arc
							(start -0.3302 -0.4318)
							(mid -0.402042 -0.402042)
							(end -0.4318 -0.3302)
						)
						(arc
							(start -0.4318 0.3302)
							(mid -0.402042 0.402042)
							(end -0.3302 0.4318)
						)
						(arc
							(start 0.3302 0.4318)
							(mid 0.402042 0.402042)
							(end 0.4318 0.3302)
						)
						(arc
							(start 0.4318 -0.3302)
							(mid 0.402042 -0.402042)
							(end 0.3302 -0.4318)
						)
					)
					(width 0)
					(fill yes)
				)
			)
		)
	)
)
